(kicad_pcb
	(version 20260206)
	(generator "pcbnew")
	(generator_version "10.0")
	(general
		(thickness 1.6)
		(legacy_teardrops no)
	)
	(paper "A4")
	(title_block
		(title "Bryce Canyon_SCC_16316-1_OCP.brd")
		(comment 1 "Bryce Canyon / footprint 64 of 1561 (U1), pads 121-238 of 1020")
	)
	(layers
		(0 "F.Cu" signal "TOP")
		(4 "In1.Cu" signal "L2GND")
		(6 "In2.Cu" signal "L3")
		(8 "In3.Cu" signal "L4VCC")
		(10 "In4.Cu" signal "L5VCC")
		(12 "In5.Cu" signal "L6")
		(14 "In6.Cu" signal "L7GND")
		(2 "B.Cu" signal "BOTTOM")
		(9 "F.Adhes" user "F.Adhesive")
		(11 "B.Adhes" user "B.Adhesive")
		(13 "F.Paste" user "Package Geometry/Pastemask Top")
		(15 "B.Paste" user "Package Geometry/Pastemask Bottom")
		(5 "F.SilkS" user "Ref Des/Silkscreen Top")
		(7 "B.SilkS" user "Ref Des/Silkscreen Bottom")
		(1 "F.Mask" user "Board Geometry/Soldermask Top")
		(3 "B.Mask" user "Board Geometry/Soldermask Bottom")
		(17 "Dwgs.User" user "User.Drawings")
		(19 "Cmts.User" user "User.Comments")
		(21 "Eco1.User" user "User.Eco1")
		(23 "Eco2.User" user "User.Eco2")
		(25 "Edge.Cuts" user "Board Geometry/Outline")
		(27 "Margin" user)
		(31 "F.CrtYd" user "Package Geometry/Place Bound Top")
		(29 "B.CrtYd" user "Package Geometry/Place Bound Bottom")
		(35 "F.Fab" user "Ref Des/Assembly Top")
		(33 "B.Fab" user "Ref Des/Assembly Bottom")
	)
	(footprint ""
		(layer "F.Cu")
		(at 115.000024 -67.00012)
		(property "Reference" "U1"
			(at 0 0 0)
			(layer "F.SilkS")
			(hide yes)
			(effects
				(font
					(size 1.27 1.27)
				)
			)
		)
		(property "Value" "LSISAS3X48-GP"
			(at -24.358092 -5.0292 0)
			(unlocked yes)
			(layer "F.Fab")
			(hide yes)
			(effects
				(font
					(size 1.016 1.016)
					(thickness 0.1524)
				)
			)
		)
		(property "Device Type" "BGA1020C33H83"
			(at -24.358092 -6.5532 0)
			(unlocked yes)
			(layer "F.Fab")
			(hide yes)
			(effects
				(font
					(size 1.016 1.016)
					(thickness 0.1524)
				)
			)
		)
		(duplicate_pad_numbers_are_jumpers no)
		(pad "AC27" smd circle
			(at 10.500106 6.500114)
			(size 0.4572 0.4572)
			(layers "F.Cu" "F.Mask" "F.Paste")
			(net "PHY_IOC_TO_SCC_C_47_DN")
		)
		(pad "AC28" smd circle
			(at 11.500104 6.500114)
			(size 0.4572 0.4572)
			(layers "F.Cu" "F.Mask" "F.Paste")
			(net "PHY_IOC_TO_SCC_C_47_DP")
		)
		(pad "AC29" smd circle
			(at 12.500102 6.500114)
			(size 0.4572 0.4572)
			(layers "F.Cu" "F.Mask" "F.Paste")
			(net "GND")
		)
		(pad "AC30" smd circle
			(at 13.5001 6.500114)
			(size 0.4572 0.4572)
			(layers "F.Cu" "F.Mask" "F.Paste")
			(net "GB_VDDA")
		)
		(pad "AC31" smd circle
			(at 14.500098 6.500114)
			(size 0.4572 0.4572)
			(layers "F.Cu" "F.Mask" "F.Paste")
			(net "PHY_SCC_TO_IOC_47_DN")
		)
		(pad "AC32" smd circle
			(at 15.500096 6.500114)
			(size 0.4572 0.4572)
			(layers "F.Cu" "F.Mask" "F.Paste")
			(net "PHY_SCC_TO_IOC_47_DP")
		)
		(pad "AD1" smd circle
			(at -15.500096 7.500112)
			(size 0.4572 0.4572)
			(layers "F.Cu" "F.Mask" "F.Paste")
			(net "DRIVE_37_ACT")
		)
		(pad "AD2" smd circle
			(at -14.500098 7.500112)
			(size 0.4572 0.4572)
			(layers "F.Cu" "F.Mask" "F.Paste")
			(net "DRIVE_39_ACT")
		)
		(pad "AD3" smd circle
			(at -13.5001 7.500112)
			(size 0.4572 0.4572)
			(layers "F.Cu" "F.Mask" "F.Paste")
			(net "GND")
		)
		(pad "AD4" smd circle
			(at -12.500102 7.500112)
			(size 0.4572 0.4572)
			(layers "F.Cu" "F.Mask" "F.Paste")
			(net "LED40")
		)
		(pad "AD5" smd circle
			(at -11.500104 7.500112)
			(size 0.4572 0.4572)
			(layers "F.Cu" "F.Mask" "F.Paste")
			(net "LED43")
		)
		(pad "AD6" smd circle
			(at -10.500106 7.500112)
			(size 0.4572 0.4572)
			(layers "F.Cu" "F.Mask" "F.Paste")
			(net "P1V8_E")
		)
		(pad "AD7" smd circle
			(at -9.500108 7.500112)
			(size 0.4572 0.4572)
			(layers "F.Cu" "F.Mask" "F.Paste")
			(net "LED44")
		)
		(pad "AD8" smd circle
			(at -8.50011 7.500112)
			(size 0.4572 0.4572)
			(layers "F.Cu" "F.Mask" "F.Paste")
			(net "GND")
		)
		(pad "AD9" smd circle
			(at -7.500112 7.500112)
			(size 0.4572 0.4572)
			(layers "F.Cu" "F.Mask" "F.Paste")
			(net "GND")
		)
		(pad "AD10" smd circle
			(at -6.500114 7.500112)
			(size 0.4572 0.4572)
			(layers "F.Cu" "F.Mask" "F.Paste")
			(net "GB_VDDA")
		)
		(pad "AD11" smd circle
			(at -5.500116 7.500112)
			(size 0.4572 0.4572)
			(layers "F.Cu" "F.Mask" "F.Paste")
			(net "GND")
		)
		(pad "AD12" smd circle
			(at -4.500118 7.500112)
			(size 0.4572 0.4572)
			(layers "F.Cu" "F.Mask" "F.Paste")
			(net "GB_VDDA")
		)
		(pad "AD13" smd circle
			(at -3.50012 7.500112)
			(size 0.4572 0.4572)
			(layers "F.Cu" "F.Mask" "F.Paste")
			(net "GND")
		)
		(pad "AD14" smd circle
			(at -2.500122 7.500112)
			(size 0.4572 0.4572)
			(layers "F.Cu" "F.Mask" "F.Paste")
			(net "GB_VDDA")
		)
		(pad "AD15" smd circle
			(at -1.500124 7.500112)
			(size 0.4572 0.4572)
			(layers "F.Cu" "F.Mask" "F.Paste")
			(net "GND")
		)
		(pad "AD16" smd circle
			(at -0.500126 7.500112)
			(size 0.4572 0.4572)
			(layers "F.Cu" "F.Mask" "F.Paste")
			(net "GB_VDDA")
		)
		(pad "AD17" smd circle
			(at 0.500126 7.500112)
			(size 0.4572 0.4572)
			(layers "F.Cu" "F.Mask" "F.Paste")
			(net "GND")
		)
		(pad "AD18" smd circle
			(at 1.500124 7.500112)
			(size 0.4572 0.4572)
			(layers "F.Cu" "F.Mask" "F.Paste")
			(net "GB_VDDA")
		)
		(pad "AD19" smd circle
			(at 2.500122 7.500112)
			(size 0.4572 0.4572)
			(layers "F.Cu" "F.Mask" "F.Paste")
			(net "GND")
		)
		(pad "AD20" smd circle
			(at 3.50012 7.500112)
			(size 0.4572 0.4572)
			(layers "F.Cu" "F.Mask" "F.Paste")
			(net "GB_VDDA")
		)
		(pad "AD21" smd circle
			(at 4.500118 7.500112)
			(size 0.4572 0.4572)
			(layers "F.Cu" "F.Mask" "F.Paste")
			(net "GND")
		)
		(pad "AD22" smd circle
			(at 5.500116 7.500112)
			(size 0.4572 0.4572)
			(layers "F.Cu" "F.Mask" "F.Paste")
			(net "GB_VDDA")
		)
		(pad "AD23" smd circle
			(at 6.500114 7.500112)
			(size 0.4572 0.4572)
			(layers "F.Cu" "F.Mask" "F.Paste")
			(net "GND")
		)
		(pad "AD24" smd circle
			(at 7.500112 7.500112)
			(size 0.4572 0.4572)
			(layers "F.Cu" "F.Mask" "F.Paste")
			(net "GND")
		)
		(pad "AD25" smd circle
			(at 8.50011 7.500112)
			(size 0.4572 0.4572)
			(layers "F.Cu" "F.Mask" "F.Paste")
			(net "GB_VDDA")
		)
		(pad "AD26" smd circle
			(at 9.500108 7.500112)
			(size 0.4572 0.4572)
			(layers "F.Cu" "F.Mask" "F.Paste")
			(net "GND")
		)
		(pad "AD27" smd circle
			(at 10.500106 7.500112)
			(size 0.4572 0.4572)
			(layers "F.Cu" "F.Mask" "F.Paste")
			(net "PHY_IOC_TO_SCC_C_46_DN")
		)
		(pad "AD28" smd circle
			(at 11.500104 7.500112)
			(size 0.4572 0.4572)
			(layers "F.Cu" "F.Mask" "F.Paste")
			(net "PHY_IOC_TO_SCC_C_46_DP")
		)
		(pad "AD29" smd circle
			(at 12.500102 7.500112)
			(size 0.4572 0.4572)
			(layers "F.Cu" "F.Mask" "F.Paste")
			(net "GB_VDDA")
		)
		(pad "AD30" smd circle
			(at 13.5001 7.500112)
			(size 0.4572 0.4572)
			(layers "F.Cu" "F.Mask" "F.Paste")
			(net "PHY_SCC_TO_IOC_46_DN")
		)
		(pad "AD31" smd circle
			(at 14.500098 7.500112)
			(size 0.4572 0.4572)
			(layers "F.Cu" "F.Mask" "F.Paste")
			(net "PHY_SCC_TO_IOC_46_DP")
		)
		(pad "AD32" smd circle
			(at 15.500096 7.500112)
			(size 0.4572 0.4572)
			(layers "F.Cu" "F.Mask" "F.Paste")
			(net "GND")
		)
		(pad "AE1" smd circle
			(at -15.500096 8.50011)
			(size 0.4572 0.4572)
			(layers "F.Cu" "F.Mask" "F.Paste")
			(net "GND")
		)
		(pad "AE2" smd circle
			(at -14.500098 8.50011)
			(size 0.4572 0.4572)
			(layers "F.Cu" "F.Mask" "F.Paste")
			(net "GND")
		)
		(pad "AE3" smd circle
			(at -13.5001 8.50011)
			(size 0.4572 0.4572)
			(layers "F.Cu" "F.Mask" "F.Paste")
			(net "P1V8_E")
		)
		(pad "AE4" smd circle
			(at -12.500102 8.50011)
			(size 0.4572 0.4572)
			(layers "F.Cu" "F.Mask" "F.Paste")
			(net "LED42")
		)
		(pad "AE5" smd circle
			(at -11.500104 8.50011)
			(size 0.4572 0.4572)
			(layers "F.Cu" "F.Mask" "F.Paste")
			(net "LED45")
		)
		(pad "AE6" smd circle
			(at -10.500106 8.50011)
			(size 0.4572 0.4572)
			(layers "F.Cu" "F.Mask" "F.Paste")
			(net "GND")
		)
		(pad "AE7" smd circle
			(at -9.500108 8.50011)
			(size 0.4572 0.4572)
			(layers "F.Cu" "F.Mask" "F.Paste")
			(net "GND")
		)
		(pad "AE8" smd circle
			(at -8.50011 8.50011)
			(size 0.4572 0.4572)
			(layers "F.Cu" "F.Mask" "F.Paste")
			(net "GND")
		)
		(pad "AE9" smd circle
			(at -7.500112 8.50011)
			(size 0.4572 0.4572)
			(layers "F.Cu" "F.Mask" "F.Paste")
			(net "GB_VDDA")
		)
		(pad "AE10" smd circle
			(at -6.500114 8.50011)
			(size 0.4572 0.4572)
			(layers "F.Cu" "F.Mask" "F.Paste")
			(net "GND")
		)
		(pad "AE11" smd circle
			(at -5.500116 8.50011)
			(size 0.4572 0.4572)
			(layers "F.Cu" "F.Mask" "F.Paste")
			(net "GB_VDDA")
		)
		(pad "AE12" smd circle
			(at -4.500118 8.50011)
			(size 0.4572 0.4572)
			(layers "F.Cu" "F.Mask" "F.Paste")
			(net "GND")
		)
		(pad "AE13" smd circle
			(at -3.50012 8.50011)
			(size 0.4572 0.4572)
			(layers "F.Cu" "F.Mask" "F.Paste")
			(net "GB_VDDA")
		)
		(pad "AE14" smd circle
			(at -2.500122 8.50011)
			(size 0.4572 0.4572)
			(layers "F.Cu" "F.Mask" "F.Paste")
			(net "GND")
		)
		(pad "AE15" smd circle
			(at -1.500124 8.50011)
			(size 0.4572 0.4572)
			(layers "F.Cu" "F.Mask" "F.Paste")
			(net "GB_VDDA")
		)
		(pad "AE16" smd circle
			(at -0.500126 8.50011)
			(size 0.4572 0.4572)
			(layers "F.Cu" "F.Mask" "F.Paste")
			(net "GND")
		)
		(pad "AE17" smd circle
			(at 0.500126 8.50011)
			(size 0.4572 0.4572)
			(layers "F.Cu" "F.Mask" "F.Paste")
			(net "GB_VDDA")
		)
		(pad "AE18" smd circle
			(at 1.500124 8.50011)
			(size 0.4572 0.4572)
			(layers "F.Cu" "F.Mask" "F.Paste")
			(net "GND")
		)
		(pad "AE19" smd circle
			(at 2.500122 8.50011)
			(size 0.4572 0.4572)
			(layers "F.Cu" "F.Mask" "F.Paste")
			(net "GB_VDDA")
		)
		(pad "AE20" smd circle
			(at 3.50012 8.50011)
			(size 0.4572 0.4572)
			(layers "F.Cu" "F.Mask" "F.Paste")
			(net "GND")
		)
		(pad "AE21" smd circle
			(at 4.500118 8.50011)
			(size 0.4572 0.4572)
			(layers "F.Cu" "F.Mask" "F.Paste")
			(net "GB_VDDA")
		)
		(pad "AE22" smd circle
			(at 5.500116 8.50011)
			(size 0.4572 0.4572)
			(layers "F.Cu" "F.Mask" "F.Paste")
			(net "GND")
		)
		(pad "AE23" smd circle
			(at 6.500114 8.50011)
			(size 0.4572 0.4572)
			(layers "F.Cu" "F.Mask" "F.Paste")
			(net "GB_VDDA")
		)
		(pad "AE24" smd circle
			(at 7.500112 8.50011)
			(size 0.4572 0.4572)
			(layers "F.Cu" "F.Mask" "F.Paste")
			(net "GND")
		)
		(pad "AE25" smd circle
			(at 8.50011 8.50011)
			(size 0.4572 0.4572)
			(layers "F.Cu" "F.Mask" "F.Paste")
			(net "GND")
		)
		(pad "AE26" smd circle
			(at 9.500108 8.50011)
			(size 0.4572 0.4572)
			(layers "F.Cu" "F.Mask" "F.Paste")
			(net "GND")
		)
		(pad "AE27" smd circle
			(at 10.500106 8.50011)
			(size 0.4572 0.4572)
			(layers "F.Cu" "F.Mask" "F.Paste")
			(net "PHY_IOC_TO_SCC_C_45_DN")
		)
		(pad "AE28" smd circle
			(at 11.500104 8.50011)
			(size 0.4572 0.4572)
			(layers "F.Cu" "F.Mask" "F.Paste")
			(net "PHY_IOC_TO_SCC_C_45_DP")
		)
		(pad "AE29" smd circle
			(at 12.500102 8.50011)
			(size 0.4572 0.4572)
			(layers "F.Cu" "F.Mask" "F.Paste")
			(net "GND")
		)
		(pad "AE30" smd circle
			(at 13.5001 8.50011)
			(size 0.4572 0.4572)
			(layers "F.Cu" "F.Mask" "F.Paste")
			(net "GB_VDDA")
		)
		(pad "AE31" smd circle
			(at 14.500098 8.50011)
			(size 0.4572 0.4572)
			(layers "F.Cu" "F.Mask" "F.Paste")
			(net "PHY_SCC_TO_IOC_45_DN")
		)
		(pad "AE32" smd circle
			(at 15.500096 8.50011)
			(size 0.4572 0.4572)
			(layers "F.Cu" "F.Mask" "F.Paste")
			(net "PHY_SCC_TO_IOC_45_DP")
		)
		(pad "AF1" smd circle
			(at -15.500096 9.500108)
			(size 0.4572 0.4572)
			(layers "F.Cu" "F.Mask" "F.Paste")
			(net "EXP_REF_CLK_P")
		)
		(pad "AF2" smd circle
			(at -14.500098 9.500108)
			(size 0.4572 0.4572)
			(layers "F.Cu" "F.Mask" "F.Paste")
			(net "EXP_REF_CLK_N")
		)
		(pad "AF3" smd circle
			(at -13.5001 9.500108)
			(size 0.4572 0.4572)
			(layers "F.Cu" "F.Mask" "F.Paste")
			(net "XTAL_VDDA18")
		)
		(pad "AF4" smd circle
			(at -12.500102 9.500108)
			(size 0.4572 0.4572)
			(layers "F.Cu" "F.Mask" "F.Paste")
			(net "GND")
		)
		(pad "AF5" smd circle
			(at -11.500104 9.500108)
			(size 0.4572 0.4572)
			(layers "F.Cu" "F.Mask" "F.Paste")
			(net "GND")
		)
		(pad "AF6" smd circle
			(at -10.500106 9.500108)
			(size 0.4572 0.4572)
			(layers "F.Cu" "F.Mask" "F.Paste")
			(net "GND")
		)
		(pad "AF7" smd circle
			(at -9.500108 9.500108)
			(size 0.4572 0.4572)
			(layers "F.Cu" "F.Mask" "F.Paste")
			(net "GND")
		)
		(pad "AF8" smd circle
			(at -8.50011 9.500108)
			(size 0.4572 0.4572)
			(layers "F.Cu" "F.Mask" "F.Paste")
			(net "GND")
		)
		(pad "AF9" smd circle
			(at -7.500112 9.500108)
			(size 0.4572 0.4572)
			(layers "F.Cu" "F.Mask" "F.Paste")
			(net "GND")
		)
		(pad "AF10" smd circle
			(at -6.500114 9.500108)
			(size 0.4572 0.4572)
			(layers "F.Cu" "F.Mask" "F.Paste")
			(net "GND")
		)
		(pad "AF11" smd circle
			(at -5.500116 9.500108)
			(size 0.4572 0.4572)
			(layers "F.Cu" "F.Mask" "F.Paste")
			(net "GND")
		)
		(pad "AF12" smd circle
			(at -4.500118 9.500108)
			(size 0.4572 0.4572)
			(layers "F.Cu" "F.Mask" "F.Paste")
			(net "GB_VDDA")
		)
		(pad "AF13" smd circle
			(at -3.50012 9.500108)
			(size 0.4572 0.4572)
			(layers "F.Cu" "F.Mask" "F.Paste")
			(net "GND")
		)
		(pad "AF14" smd circle
			(at -2.500122 9.500108)
			(size 0.4572 0.4572)
			(layers "F.Cu" "F.Mask" "F.Paste")
			(net "GB_VDDA")
		)
		(pad "AF15" smd circle
			(at -1.500124 9.500108)
			(size 0.4572 0.4572)
			(layers "F.Cu" "F.Mask" "F.Paste")
			(net "GND")
		)
		(pad "AF16" smd circle
			(at -0.500126 9.500108)
			(size 0.4572 0.4572)
			(layers "F.Cu" "F.Mask" "F.Paste")
			(net "GB_VDDA")
		)
		(pad "AF17" smd circle
			(at 0.500126 9.500108)
			(size 0.4572 0.4572)
			(layers "F.Cu" "F.Mask" "F.Paste")
			(net "GND")
		)
		(pad "AF18" smd circle
			(at 1.500124 9.500108)
			(size 0.4572 0.4572)
			(layers "F.Cu" "F.Mask" "F.Paste")
			(net "GB_VDDA")
		)
		(pad "AF19" smd circle
			(at 2.500122 9.500108)
			(size 0.4572 0.4572)
			(layers "F.Cu" "F.Mask" "F.Paste")
			(net "GND")
		)
		(pad "AF20" smd circle
			(at 3.50012 9.500108)
			(size 0.4572 0.4572)
			(layers "F.Cu" "F.Mask" "F.Paste")
			(net "GB_VDDA")
		)
		(pad "AF21" smd circle
			(at 4.500118 9.500108)
			(size 0.4572 0.4572)
			(layers "F.Cu" "F.Mask" "F.Paste")
			(net "GND")
		)
		(pad "AF22" smd circle
			(at 5.500116 9.500108)
			(size 0.4572 0.4572)
			(layers "F.Cu" "F.Mask" "F.Paste")
			(net "GB_VDDA")
		)
		(pad "AF23" smd circle
			(at 6.500114 9.500108)
			(size 0.4572 0.4572)
			(layers "F.Cu" "F.Mask" "F.Paste")
			(net "GND")
		)
		(pad "AF24" smd circle
			(at 7.500112 9.500108)
			(size 0.4572 0.4572)
			(layers "F.Cu" "F.Mask" "F.Paste")
			(net "GB_VDDA")
		)
		(pad "AF25" smd circle
			(at 8.50011 9.500108)
			(size 0.4572 0.4572)
			(layers "F.Cu" "F.Mask" "F.Paste")
			(net "GND")
		)
		(pad "AF26" smd circle
			(at 9.500108 9.500108)
			(size 0.4572 0.4572)
			(layers "F.Cu" "F.Mask" "F.Paste")
			(net "GND")
		)
		(pad "AF27" smd circle
			(at 10.500106 9.500108)
			(size 0.4572 0.4572)
			(layers "F.Cu" "F.Mask" "F.Paste")
			(net "PHY_IOC_TO_SCC_C_44_DN")
		)
		(pad "AF28" smd circle
			(at 11.500104 9.500108)
			(size 0.4572 0.4572)
			(layers "F.Cu" "F.Mask" "F.Paste")
			(net "PHY_IOC_TO_SCC_C_44_DP")
		)
		(pad "AF29" smd circle
			(at 12.500102 9.500108)
			(size 0.4572 0.4572)
			(layers "F.Cu" "F.Mask" "F.Paste")
			(net "GB_VDDA")
		)
		(pad "AF30" smd circle
			(at 13.5001 9.500108)
			(size 0.4572 0.4572)
			(layers "F.Cu" "F.Mask" "F.Paste")
			(net "PHY_SCC_TO_IOC_44_DN")
		)
		(pad "AF31" smd circle
			(at 14.500098 9.500108)
			(size 0.4572 0.4572)
			(layers "F.Cu" "F.Mask" "F.Paste")
			(net "PHY_SCC_TO_IOC_44_DP")
		)
		(pad "AF32" smd circle
			(at 15.500096 9.500108)
			(size 0.4572 0.4572)
			(layers "F.Cu" "F.Mask" "F.Paste")
			(net "GND")
		)
		(pad "AG1" smd circle
			(at -15.500096 10.500106)
			(size 0.4572 0.4572)
			(layers "F.Cu" "F.Mask" "F.Paste")
			(net "GND")
		)
		(pad "AG2" smd circle
			(at -14.500098 10.500106)
			(size 0.4572 0.4572)
			(layers "F.Cu" "F.Mask" "F.Paste")
			(net "GND")
		)
		(pad "AG3" smd circle
			(at -13.5001 10.500106)
			(size 0.4572 0.4572)
			(layers "F.Cu" "F.Mask" "F.Paste")
			(net "PHY_DPB_TO_SCC_C_13_DN")
		)
		(pad "AG4" smd circle
			(at -12.500102 10.500106)
			(size 0.4572 0.4572)
			(layers "F.Cu" "F.Mask" "F.Paste")
			(net "PHY_DPB_TO_SCC_C_14_DN")
		)
		(pad "AG5" smd circle
			(at -11.500104 10.500106)
			(size 0.4572 0.4572)
			(layers "F.Cu" "F.Mask" "F.Paste")
			(net "PHY_DPB_TO_SCC_C_15_DN")
		)
		(pad "AG6" smd circle
			(at -10.500106 10.500106)
			(size 0.4572 0.4572)
			(layers "F.Cu" "F.Mask" "F.Paste")
			(net "PHY_DPB_TO_SCC_C_16_DN")
		)
		(pad "AG7" smd circle
			(at -9.500108 10.500106)
			(size 0.4572 0.4572)
			(layers "F.Cu" "F.Mask" "F.Paste")
			(net "PHY_DPB_TO_SCC_C_17_DN")
		)
		(pad "AG8" smd circle
			(at -8.50011 10.500106)
			(size 0.4572 0.4572)
			(layers "F.Cu" "F.Mask" "F.Paste")
			(net "PHY_DPB_TO_SCC_C_18_DN")
		)
		(pad "AG9" smd circle
			(at -7.500112 10.500106)
			(size 0.4572 0.4572)
			(layers "F.Cu" "F.Mask" "F.Paste")
			(net "PHY_DPB_TO_SCC_C_19_DN")
		)
		(pad "AG10" smd circle
			(at -6.500114 10.500106)
			(size 0.4572 0.4572)
			(layers "F.Cu" "F.Mask" "F.Paste")
			(net "PHY_DPB_TO_SCC_C_20_DN")
		)
		(pad "AG11" smd circle
			(at -5.500116 10.500106)
			(size 0.4572 0.4572)
			(layers "F.Cu" "F.Mask" "F.Paste")
			(net "PHY_DPB_TO_SCC_C_21_DN")
		)
		(pad "AG12" smd circle
			(at -4.500118 10.500106)
			(size 0.4572 0.4572)
			(layers "F.Cu" "F.Mask" "F.Paste")
			(net "PHY_DPB_TO_SCC_C_22_DN")
		)
		(pad "AG13" smd circle
			(at -3.50012 10.500106)
			(size 0.4572 0.4572)
			(layers "F.Cu" "F.Mask" "F.Paste")
			(net "PHY_DPB_TO_SCC_C_23_DN")
		)
		(pad "AG14" smd circle
			(at -2.500122 10.500106)
			(size 0.4572 0.4572)
			(layers "F.Cu" "F.Mask" "F.Paste")
			(net "PHY_DPB_TO_SCC_C_24_DN")
		)
		(pad "AG15" smd circle
			(at -1.500124 10.500106)
			(size 0.4572 0.4572)
			(layers "F.Cu" "F.Mask" "F.Paste")
			(net "PHY_DPB_TO_SCC_C_25_DN")
		)
		(pad "AG16" smd circle
			(at -0.500126 10.500106)
			(size 0.4572 0.4572)
			(layers "F.Cu" "F.Mask" "F.Paste")
			(net "PHY_DPB_TO_SCC_C_26_DN")
		)
	)
)
